# S9S_MB_2U (Grand Teton) — schematic netlist excerpt (pin names and nets, part order shuffled) for the footprints in the layout excerpt that follows; sources: Cadence DE-HDL packaged netlist, KiCad conversion of 03242023_DA0F0TMBIJ0_F0T_Motherboard_J_brd_V01_OCP.brd

U53  74LVC1G08W57  74LVC1G08W5-7 IC  pkg SOT25-5_0-95_3X1-6  page 164
  A  = HP_LVC3_OCP_V3_2_PWRGD_R
  B  = RST_OCP_V3_2_N
  GND  = GND
  Y  = RST_HP_OCP_V3_2_N
  VCC  = P3V3_AUX

C942  Q_CAP_DIFFBUS  DIFF BUS_0.22UF 6.3V 20% X6S  pkg C0201  page 173 : \1\ = P5E_CPU0_PE2_TX_C_DN<11> ; \2\ = P5E_CPU0_PE2_TX_DN<11>
PC723_P0_4  Q_CAP  22UF 16V 20% X6S  pkg C0805  page 272 : A = SW_P12V_PVCCFA_EHV_FIVRA_CPU0_L ; B = GND

(kicad_pcb
	(version 20260206)
	(generator "pcbnew")
	(generator_version "10.0")
	(general
		(thickness 1.6)
		(legacy_teardrops no)
	)
	(paper "A4")
	(title_block
		(title "03242023_DA0F0TMBIJ0_F0T_Motherboard_J_brd_V01_OCP.brd")
		(comment 1 "Grand Teton / footprints 3137-3139 of 6105")
	)
	(layers
		(0 "F.Cu" signal "TOP")
		(4 "In1.Cu" signal "GND")
		(6 "In2.Cu" signal "IN1")
		(8 "In3.Cu" signal "GND1")
		(10 "In4.Cu" signal "IN2")
		(12 "In5.Cu" signal "GND2")
		(14 "In6.Cu" signal "IN3")
		(16 "In7.Cu" signal "GND3")
		(18 "In8.Cu" signal "VCC")
		(20 "In9.Cu" signal "VCC1")
		(22 "In10.Cu" signal "GND4")
		(24 "In11.Cu" signal "IN4")
		(26 "In12.Cu" signal "GND5")
		(28 "In13.Cu" signal "IN5")
		(30 "In14.Cu" signal "GND6")
		(32 "In15.Cu" signal "IN6")
		(34 "In16.Cu" signal "GND7")
		(2 "B.Cu" signal "BOTTOM")
		(9 "F.Adhes" user "F.Adhesive")
		(11 "B.Adhes" user "B.Adhesive")
		(13 "F.Paste" user "Package Geometry/Pastemask Top")
		(15 "B.Paste" user "Package Geometry/Pastemask Bottom")
		(5 "F.SilkS" user "Ref Des/Silkscreen Top")
		(7 "B.SilkS" user "Ref Des/Silkscreen Bottom")
		(1 "F.Mask" user "Board Geometry/Soldermask Top")
		(3 "B.Mask" user "Board Geometry/Soldermask Bottom")
		(17 "Dwgs.User" user "User.Drawings")
		(19 "Cmts.User" user "User.Comments")
		(21 "Eco1.User" user "User.Eco1")
		(23 "Eco2.User" user "User.Eco2")
		(25 "Edge.Cuts" user "Board Geometry/Outline")
		(27 "Margin" user)
		(31 "F.CrtYd" user "Package Geometry/Place Bound Top")
		(29 "B.CrtYd" user "Package Geometry/Place Bound Bottom")
		(35 "F.Fab" user "Ref Des/Assembly Top")
		(33 "B.Fab" user "Ref Des/Assembly Bottom")
	)
	(footprint ""
		(layer "F.Cu")
		(at 384.56489 -402.371052 -90)
		(property "Reference" "C942"
			(at 0 0 270)
			(layer "F.SilkS")
			(hide yes)
			(effects
				(font
					(size 1.27 1.27)
				)
			)
		)
		(property "Value" ""
			(at 0 0 270)
			(layer "F.Fab")
			(effects
				(font
					(size 1.27 1.27)
				)
			)
		)
		(duplicate_pad_numbers_are_jumpers no)
		(fp_line
			(start -0.299974 0.150114)
			(end -0.299974 -0.150114)
			(stroke
				(width 0.1)
				(type default)
			)
			(layer "F.Fab")
		)
		(fp_line
			(start 0.299974 0.150114)
			(end -0.299974 0.150114)
			(stroke
				(width 0.1)
				(type default)
			)
			(layer "F.Fab")
		)
		(fp_line
			(start -0.299974 -0.150114)
			(end 0.299974 -0.150114)
			(stroke
				(width 0.1)
				(type default)
			)
			(layer "F.Fab")
		)
		(fp_line
			(start 0.299974 -0.150114)
			(end 0.299974 0.150114)
			(stroke
				(width 0.1)
				(type default)
			)
			(layer "F.Fab")
		)
		(pad "1" smd rect
			(at -0.2667 0 270)
			(size 0.3048 0.381)
			(layers "F.Cu" "F.Mask" "F.Paste")
			(net "P5E_CPU0_PE2_TX_C_DN<11>")
		)
		(pad "2" smd rect
			(at 0.2667 0 270)
			(size 0.3048 0.381)
			(layers "F.Cu" "F.Mask" "F.Paste")
			(net "P5E_CPU0_PE2_TX_DN<11>")
		)
	)
	(footprint ""
		(layer "F.Cu")
		(at 293.078916 -367.345976)
		(property "Reference" "PC723_P0_4"
			(at 0 0 0)
			(layer "F.SilkS")
			(hide yes)
			(effects
				(font
					(size 1.27 1.27)
				)
			)
		)
		(property "Value" ""
			(at 0 0 0)
			(layer "F.Fab")
			(effects
				(font
					(size 1.27 1.27)
				)
			)
		)
		(duplicate_pad_numbers_are_jumpers no)
		(fp_line
			(start -1.524 -0.762)
			(end 1.524 -0.762)
			(stroke
				(width 0.1524)
				(type default)
			)
			(layer "F.SilkS")
		)
		(fp_line
			(start -1.524 0.762)
			(end -1.524 -0.762)
			(stroke
				(width 0.1524)
				(type default)
			)
			(layer "F.SilkS")
		)
		(fp_line
			(start 1.524 -0.762)
			(end 1.524 0.762)
			(stroke
				(width 0.1524)
				(type default)
			)
			(layer "F.SilkS")
		)
		(fp_line
			(start 1.524 0.762)
			(end -1.524 0.762)
			(stroke
				(width 0.1524)
				(type default)
			)
			(layer "F.SilkS")
		)
		(fp_line
			(start -1.1049 -0.724916)
			(end -1.1049 0.724916)
			(stroke
				(width 0.1)
				(type default)
			)
			(layer "F.Fab")
		)
		(fp_line
			(start -1.1049 0.724916)
			(end 1.1049 0.724916)
			(stroke
				(width 0.1)
				(type default)
			)
			(layer "F.Fab")
		)
		(fp_line
			(start 1.1049 -0.724916)
			(end -1.1049 -0.724916)
			(stroke
				(width 0.1)
				(type default)
			)
			(layer "F.Fab")
		)
		(fp_line
			(start 1.1049 0.724916)
			(end 1.1049 -0.724916)
			(stroke
				(width 0.1)
				(type default)
			)
			(layer "F.Fab")
		)
		(pad "1" smd rect
			(at -0.889 0 180)
			(size 1.016 1.27)
			(layers "F.Cu" "F.Mask" "F.Paste")
			(net "SW_P12V_PVCCFA_EHV_FIVRA_CPU0_L")
		)
		(pad "2" smd rect
			(at 0.889 0 180)
			(size 1.016 1.27)
			(layers "F.Cu" "F.Mask" "F.Paste")
			(net "GND")
		)
	)
	(footprint ""
		(layer "F.Cu")
		(at 89.5604 -38.659308)
		(property "Reference" "U53"
			(at -0.28448 -2.553208 0)
			(unlocked yes)
			(layer "F.SilkS")
			(effects
				(font
					(size 0.7874 0.5842)
					(thickness 0.1524)
				)
				(justify left)
			)
		)
		(property "Value" ""
			(at 0 0 0)
			(layer "F.Fab")
			(effects
				(font
					(size 1.27 1.27)
				)
			)
		)
		(duplicate_pad_numbers_are_jumpers no)
		(fp_line
			(start -1.733296 -1.549908)
			(end -1.733296 1.549908)
			(stroke
				(width 0.1524)
				(type default)
			)
			(layer "F.SilkS")
		)
		(fp_line
			(start -1.733296 1.549908)
			(end 1.733296 1.549908)
			(stroke
				(width 0.1524)
				(type default)
			)
			(layer "F.SilkS")
		)
		(fp_line
			(start -0.660908 -1.549908)
			(end -1.733296 -1.549908)
			(stroke
				(width 0.1524)
				(type default)
			)
			(layer "F.SilkS")
		)
		(fp_line
			(start 0 -0.889)
			(end -0.660908 -1.549908)
			(stroke
				(width 0.1524)
				(type default)
			)
			(layer "F.SilkS")
		)
		(fp_line
			(start 0.660908 -1.549908)
			(end 0 -0.889)
			(stroke
				(width 0.1524)
				(type default)
			)
			(layer "F.SilkS")
		)
		(fp_line
			(start 1.733296 -1.549908)
			(end 0.660908 -1.549908)
			(stroke
				(width 0.1524)
				(type default)
			)
			(layer "F.SilkS")
		)
		(fp_line
			(start 1.733296 1.549908)
			(end 1.733296 -1.549908)
			(stroke
				(width 0.1524)
				(type default)
			)
			(layer "F.SilkS")
		)
		(fp_poly
			(pts
				(xy -0.92456 -2.2479) (xy -1.17856 -1.7399) (xy -1.43256 -2.2479)
			)
			(stroke
				(width 0)
				(type default)
			)
			(fill yes)
			(layer "F.SilkS")
		)
		(fp_line
			(start -0.849884 -1.549908)
			(end -0.849884 1.549908)
			(stroke
				(width 0.1)
				(type default)
			)
			(layer "F.Fab")
		)
		(fp_line
			(start -0.849884 1.549908)
			(end 0.849884 1.549908)
			(stroke
				(width 0.1)
				(type default)
			)
			(layer "F.Fab")
		)
		(fp_line
			(start 0.849884 -1.549908)
			(end -0.849884 -1.549908)
			(stroke
				(width 0.1)
				(type default)
			)
			(layer "F.Fab")
		)
		(fp_line
			(start 0.849884 1.549908)
			(end 0.849884 -1.549908)
			(stroke
				(width 0.1)
				(type default)
			)
			(layer "F.Fab")
		)
		(fp_poly
			(pts
				(xy -2.4384 -1.20396) (xy -2.4384 -0.69596) (xy -1.9304 -0.94996)
			)
			(stroke
				(width 0)
				(type default)
			)
			(fill yes)
			(layer "F.Fab")
		)
		(pad "1" smd rect
			(at -1.199896 -0.94996 270)
			(size 0.5588 0.8128)
			(layers "F.Cu" "F.Mask" "F.Paste")
			(net "HP_LVC3_OCP_V3_2_PWRGD_R")
		)
		(pad "2" smd rect
			(at -1.199896 0 270)
			(size 0.5588 0.8128)
			(layers "F.Cu" "F.Mask" "F.Paste")
			(net "RST_OCP_V3_2_N")
		)
		(pad "3" smd rect
			(at -1.199896 0.94996 270)
			(size 0.5588 0.8128)
			(layers "F.Cu" "F.Mask" "F.Paste")
			(net "GND")
		)
		(pad "4" smd rect
			(at 1.199896 0.94996 270)
			(size 0.5588 0.8128)
			(layers "F.Cu" "F.Mask" "F.Paste")
			(net "RST_HP_OCP_V3_2_N")
		)
		(pad "5" smd rect
			(at 1.199896 -0.94996 270)
			(size 0.5588 0.8128)
			(layers "F.Cu" "F.Mask" "F.Paste")
			(net "P3V3_AUX")
		)
	)
)
